(kicad_pcb
	(version 20260206)
	(generator "pcbnew")
	(generator_version "10.0")
	(general
		(thickness 1.6)
		(legacy_teardrops no)
	)
	(paper "A4")
	(title_block
		(title "04192023_DAF0TMB3IC0_F0TG_MB_C_brd_V02_OCP.brd")
		(comment 1 "Grand Teton / footprints 4672-4677 of 8354")
	)
	(layers
		(0 "F.Cu" signal "TOP")
		(4 "In1.Cu" signal "GND")
		(6 "In2.Cu" signal "IN1")
		(8 "In3.Cu" signal "GND1")
		(10 "In4.Cu" signal "IN2")
		(12 "In5.Cu" signal "GND2")
		(14 "In6.Cu" signal "IN3")
		(16 "In7.Cu" signal "GND3")
		(18 "In8.Cu" signal "VCC")
		(20 "In9.Cu" signal "VCC1")
		(22 "In10.Cu" signal "GND4")
		(24 "In11.Cu" signal "IN4")
		(26 "In12.Cu" signal "GND5")
		(28 "In13.Cu" signal "IN5")
		(30 "In14.Cu" signal "GND6")
		(32 "In15.Cu" signal "IN6")
		(34 "In16.Cu" signal "GND7")
		(2 "B.Cu" signal "BOTTOM")
		(9 "F.Adhes" user "F.Adhesive")
		(11 "B.Adhes" user "B.Adhesive")
		(13 "F.Paste" user "Package Geometry/Pastemask Top")
		(15 "B.Paste" user "Package Geometry/Pastemask Bottom")
		(5 "F.SilkS" user "Ref Des/Silkscreen Top")
		(7 "B.SilkS" user "Ref Des/Silkscreen Bottom")
		(1 "F.Mask" user "Board Geometry/Soldermask Top")
		(3 "B.Mask" user "Board Geometry/Soldermask Bottom")
		(17 "Dwgs.User" user "User.Drawings")
		(19 "Cmts.User" user "User.Comments")
		(21 "Eco1.User" user "User.Eco1")
		(23 "Eco2.User" user "User.Eco2")
		(25 "Edge.Cuts" user "Board Geometry/Outline")
		(27 "Margin" user)
		(31 "F.CrtYd" user "Package Geometry/Place Bound Top")
		(29 "B.CrtYd" user "Package Geometry/Place Bound Bottom")
		(35 "F.Fab" user "Ref Des/Assembly Top")
		(33 "B.Fab" user "Ref Des/Assembly Bottom")
	)
	(footprint ""
		(layer "F.Cu")
		(at 86.311994 -31.667958 90)
		(property "Reference" "R4602"
			(at 0 0 90)
			(layer "F.SilkS")
			(hide yes)
			(effects
				(font
					(size 1.27 1.27)
				)
			)
		)
		(property "Value" ""
			(at 0 0 90)
			(layer "F.Fab")
			(effects
				(font
					(size 1.27 1.27)
				)
			)
		)
		(duplicate_pad_numbers_are_jumpers no)
		(fp_line
			(start 0.7874 -0.4064)
			(end 0.7874 0.4064)
			(stroke
				(width 0.1524)
				(type default)
			)
			(layer "F.SilkS")
		)
		(fp_line
			(start -0.7874 -0.4064)
			(end 0.7874 -0.4064)
			(stroke
				(width 0.1524)
				(type default)
			)
			(layer "F.SilkS")
		)
		(fp_line
			(start 0.7874 0.4064)
			(end -0.7874 0.4064)
			(stroke
				(width 0.1524)
				(type default)
			)
			(layer "F.SilkS")
		)
		(fp_line
			(start -0.7874 0.4064)
			(end -0.7874 -0.4064)
			(stroke
				(width 0.1524)
				(type default)
			)
			(layer "F.SilkS")
		)
		(fp_line
			(start -0.12065 -0.305054)
			(end -0.12065 -0.2794)
			(stroke
				(width 0.1)
				(type default)
			)
			(layer "F.Fab")
		)
		(fp_line
			(start -0.67945 -0.305054)
			(end -0.12065 -0.305054)
			(stroke
				(width 0.1)
				(type default)
			)
			(layer "F.Fab")
		)
		(fp_line
			(start 0.67945 -0.3048)
			(end 0.67945 0.3048)
			(stroke
				(width 0.1)
				(type default)
			)
			(layer "F.Fab")
		)
		(fp_line
			(start 0.12065 -0.3048)
			(end 0.67945 -0.3048)
			(stroke
				(width 0.1)
				(type default)
			)
			(layer "F.Fab")
		)
		(fp_line
			(start 0.12065 -0.2794)
			(end 0.12065 -0.3048)
			(stroke
				(width 0.1)
				(type default)
			)
			(layer "F.Fab")
		)
		(fp_line
			(start -0.12065 -0.2794)
			(end 0.12065 -0.2794)
			(stroke
				(width 0.1)
				(type default)
			)
			(layer "F.Fab")
		)
		(fp_line
			(start 0.120396 0.2794)
			(end -0.12065 0.2794)
			(stroke
				(width 0.1)
				(type default)
			)
			(layer "F.Fab")
		)
		(fp_line
			(start -0.12065 0.2794)
			(end -0.12065 0.3048)
			(stroke
				(width 0.1)
				(type default)
			)
			(layer "F.Fab")
		)
		(fp_line
			(start 0.67945 0.3048)
			(end 0.120396 0.3048)
			(stroke
				(width 0.1)
				(type default)
			)
			(layer "F.Fab")
		)
		(fp_line
			(start 0.120396 0.3048)
			(end 0.120396 0.2794)
			(stroke
				(width 0.1)
				(type default)
			)
			(layer "F.Fab")
		)
		(fp_line
			(start -0.12065 0.3048)
			(end -0.67945 0.3048)
			(stroke
				(width 0.1)
				(type default)
			)
			(layer "F.Fab")
		)
		(fp_line
			(start -0.67945 0.3048)
			(end -0.67945 -0.305054)
			(stroke
				(width 0.1)
				(type default)
			)
			(layer "F.Fab")
		)
		(pad "1" smd circle
			(at -0.40005 0 90)
			(size 0 0)
			(layers "F.Cu" "F.Mask" "F.Paste")
			(net "CLK_50M_NCSI_OCP_V3_2_ISO")
		)
		(pad "2" smd circle
			(at 0.40005 0 90)
			(size 0 0)
			(layers "F.Cu" "F.Mask" "F.Paste")
			(net "CLK_50M_NCSI_OCP_V3_2_ISO_R")
		)
	)
	(footprint ""
		(layer "F.Cu")
		(at 297.330368 -148.493988)
		(property "Reference" "R5007"
			(at 0 0 0)
			(layer "F.SilkS")
			(hide yes)
			(effects
				(font
					(size 1.27 1.27)
				)
			)
		)
		(property "Value" ""
			(at 0 0 0)
			(layer "F.Fab")
			(effects
				(font
					(size 1.27 1.27)
				)
			)
		)
		(duplicate_pad_numbers_are_jumpers no)
		(fp_line
			(start -0.7874 -0.4064)
			(end 0.7874 -0.4064)
			(stroke
				(width 0.1524)
				(type default)
			)
			(layer "F.SilkS")
		)
		(fp_line
			(start -0.7874 0.4064)
			(end -0.7874 -0.4064)
			(stroke
				(width 0.1524)
				(type default)
			)
			(layer "F.SilkS")
		)
		(fp_line
			(start 0.7874 -0.4064)
			(end 0.7874 0.4064)
			(stroke
				(width 0.1524)
				(type default)
			)
			(layer "F.SilkS")
		)
		(fp_line
			(start 0.7874 0.4064)
			(end -0.7874 0.4064)
			(stroke
				(width 0.1524)
				(type default)
			)
			(layer "F.SilkS")
		)
		(fp_line
			(start -0.67945 -0.305054)
			(end -0.12065 -0.305054)
			(stroke
				(width 0.1)
				(type default)
			)
			(layer "F.Fab")
		)
		(fp_line
			(start -0.67945 0.3048)
			(end -0.67945 -0.305054)
			(stroke
				(width 0.1)
				(type default)
			)
			(layer "F.Fab")
		)
		(fp_line
			(start -0.12065 -0.305054)
			(end -0.12065 -0.2794)
			(stroke
				(width 0.1)
				(type default)
			)
			(layer "F.Fab")
		)
		(fp_line
			(start -0.12065 -0.2794)
			(end 0.12065 -0.2794)
			(stroke
				(width 0.1)
				(type default)
			)
			(layer "F.Fab")
		)
		(fp_line
			(start -0.12065 0.2794)
			(end -0.12065 0.3048)
			(stroke
				(width 0.1)
				(type default)
			)
			(layer "F.Fab")
		)
		(fp_line
			(start -0.12065 0.3048)
			(end -0.67945 0.3048)
			(stroke
				(width 0.1)
				(type default)
			)
			(layer "F.Fab")
		)
		(fp_line
			(start 0.120396 0.2794)
			(end -0.12065 0.2794)
			(stroke
				(width 0.1)
				(type default)
			)
			(layer "F.Fab")
		)
		(fp_line
			(start 0.120396 0.3048)
			(end 0.120396 0.2794)
			(stroke
				(width 0.1)
				(type default)
			)
			(layer "F.Fab")
		)
		(fp_line
			(start 0.12065 -0.3048)
			(end 0.67945 -0.3048)
			(stroke
				(width 0.1)
				(type default)
			)
			(layer "F.Fab")
		)
		(fp_line
			(start 0.12065 -0.2794)
			(end 0.12065 -0.3048)
			(stroke
				(width 0.1)
				(type default)
			)
			(layer "F.Fab")
		)
		(fp_line
			(start 0.67945 -0.3048)
			(end 0.67945 0.3048)
			(stroke
				(width 0.1)
				(type default)
			)
			(layer "F.Fab")
		)
		(fp_line
			(start 0.67945 0.3048)
			(end 0.120396 0.3048)
			(stroke
				(width 0.1)
				(type default)
			)
			(layer "F.Fab")
		)
		(pad "1" smd circle
			(at -0.40005 0)
			(size 0 0)
			(layers "F.Cu" "F.Mask" "F.Paste")
			(net "PVDD11_S3_P0")
		)
		(pad "2" smd circle
			(at 0.40005 0)
			(size 0 0)
			(layers "F.Cu" "F.Mask" "F.Paste")
			(net "I3C_SPD_DDRAF_CPU0_LVC1_SDA")
		)
	)
	(footprint ""
		(layer "F.Cu")
		(at 92.178632 -69.84238 180)
		(property "Reference" "PC2173"
			(at 0 0 180)
			(layer "F.SilkS")
			(hide yes)
			(effects
				(font
					(size 1.27 1.27)
				)
			)
		)
		(property "Value" ""
			(at 0 0 180)
			(layer "F.Fab")
			(effects
				(font
					(size 1.27 1.27)
				)
			)
		)
		(duplicate_pad_numbers_are_jumpers no)
		(fp_line
			(start 1.524 0.762)
			(end -1.524 0.762)
			(stroke
				(width 0.1524)
				(type default)
			)
			(layer "F.SilkS")
		)
		(fp_line
			(start 1.524 -0.762)
			(end 1.524 0.762)
			(stroke
				(width 0.1524)
				(type default)
			)
			(layer "F.SilkS")
		)
		(fp_line
			(start -1.524 0.762)
			(end -1.524 -0.762)
			(stroke
				(width 0.1524)
				(type default)
			)
			(layer "F.SilkS")
		)
		(fp_line
			(start -1.524 -0.762)
			(end 1.524 -0.762)
			(stroke
				(width 0.1524)
				(type default)
			)
			(layer "F.SilkS")
		)
		(fp_line
			(start 1.1049 0.724916)
			(end 1.1049 -0.724916)
			(stroke
				(width 0.1)
				(type default)
			)
			(layer "F.Fab")
		)
		(fp_line
			(start 1.1049 -0.724916)
			(end -1.1049 -0.724916)
			(stroke
				(width 0.1)
				(type default)
			)
			(layer "F.Fab")
		)
		(fp_line
			(start -1.1049 0.724916)
			(end 1.1049 0.724916)
			(stroke
				(width 0.1)
				(type default)
			)
			(layer "F.Fab")
		)
		(fp_line
			(start -1.1049 -0.724916)
			(end -1.1049 0.724916)
			(stroke
				(width 0.1)
				(type default)
			)
			(layer "F.Fab")
		)
		(pad "1" smd rect
			(at -0.889 0)
			(size 1.016 1.27)
			(layers "F.Cu" "F.Mask" "F.Paste")
			(net "P3V3_OCP_V3_2_R")
		)
		(pad "2" smd rect
			(at 0.889 0)
			(size 1.016 1.27)
			(layers "F.Cu" "F.Mask" "F.Paste")
			(net "GND")
		)
	)
	(footprint ""
		(layer "F.Cu")
		(at 355.300534 -340.084664 -90)
		(property "Reference" "PC115_6"
			(at 0 0 270)
			(layer "F.SilkS")
			(hide yes)
			(effects
				(font
					(size 1.27 1.27)
				)
			)
		)
		(property "Value" ""
			(at 0 0 270)
			(layer "F.Fab")
			(effects
				(font
					(size 1.27 1.27)
				)
			)
		)
		(duplicate_pad_numbers_are_jumpers no)
		(fp_line
			(start -0.7874 0.4064)
			(end -0.7874 -0.4064)
			(stroke
				(width 0.1524)
				(type default)
			)
			(layer "F.SilkS")
		)
		(fp_line
			(start 0.7874 0.4064)
			(end -0.7874 0.4064)
			(stroke
				(width 0.1524)
				(type default)
			)
			(layer "F.SilkS")
		)
		(fp_line
			(start -0.7874 -0.4064)
			(end 0.7874 -0.4064)
			(stroke
				(width 0.1524)
				(type default)
			)
			(layer "F.SilkS")
		)
		(fp_line
			(start 0.7874 -0.4064)
			(end 0.7874 0.4064)
			(stroke
				(width 0.1524)
				(type default)
			)
			(layer "F.SilkS")
		)
		(fp_line
			(start -0.67945 0.3048)
			(end -0.67945 -0.305054)
			(stroke
				(width 0.1)
				(type default)
			)
			(layer "F.Fab")
		)
		(fp_line
			(start -0.12065 0.3048)
			(end -0.67945 0.3048)
			(stroke
				(width 0.1)
				(type default)
			)
			(layer "F.Fab")
		)
		(fp_line
			(start 0.120396 0.3048)
			(end 0.120396 0.2794)
			(stroke
				(width 0.1)
				(type default)
			)
			(layer "F.Fab")
		)
		(fp_line
			(start 0.67945 0.3048)
			(end 0.120396 0.3048)
			(stroke
				(width 0.1)
				(type default)
			)
			(layer "F.Fab")
		)
		(fp_line
			(start -0.12065 0.2794)
			(end -0.12065 0.3048)
			(stroke
				(width 0.1)
				(type default)
			)
			(layer "F.Fab")
		)
		(fp_line
			(start 0.120396 0.2794)
			(end -0.12065 0.2794)
			(stroke
				(width 0.1)
				(type default)
			)
			(layer "F.Fab")
		)
		(fp_line
			(start -0.12065 -0.2794)
			(end 0.12065 -0.2794)
			(stroke
				(width 0.1)
				(type default)
			)
			(layer "F.Fab")
		)
		(fp_line
			(start 0.12065 -0.2794)
			(end 0.12065 -0.3048)
			(stroke
				(width 0.1)
				(type default)
			)
			(layer "F.Fab")
		)
		(fp_line
			(start 0.12065 -0.3048)
			(end 0.67945 -0.3048)
			(stroke
				(width 0.1)
				(type default)
			)
			(layer "F.Fab")
		)
		(fp_line
			(start 0.67945 -0.3048)
			(end 0.67945 0.3048)
			(stroke
				(width 0.1)
				(type default)
			)
			(layer "F.Fab")
		)
		(fp_line
			(start -0.67945 -0.305054)
			(end -0.12065 -0.305054)
			(stroke
				(width 0.1)
				(type default)
			)
			(layer "F.Fab")
		)
		(fp_line
			(start -0.12065 -0.305054)
			(end -0.12065 -0.2794)
			(stroke
				(width 0.1)
				(type default)
			)
			(layer "F.Fab")
		)
		(pad "1" smd circle
			(at -0.40005 0 270)
			(size 0 0)
			(layers "F.Cu" "F.Mask" "F.Paste")
			(net "SW_P12V_AUX_PVDDCR_CPU1_P0_FLT")
		)
		(pad "2" smd circle
			(at 0.40005 0 270)
			(size 0 0)
			(layers "F.Cu" "F.Mask" "F.Paste")
			(net "GND")
		)
	)
	(footprint ""
		(layer "F.Cu")
		(at 73.393046 -62.969394 -90)
		(property "Reference" "R1173"
			(at 0 0 270)
			(layer "F.SilkS")
			(hide yes)
			(effects
				(font
					(size 1.27 1.27)
				)
			)
		)
		(property "Value" ""
			(at 0 0 270)
			(layer "F.Fab")
			(effects
				(font
					(size 1.27 1.27)
				)
			)
		)
		(duplicate_pad_numbers_are_jumpers no)
		(fp_line
			(start -0.7874 0.4064)
			(end -0.7874 -0.4064)
			(stroke
				(width 0.1524)
				(type default)
			)
			(layer "F.SilkS")
		)
		(fp_line
			(start 0.7874 0.4064)
			(end -0.7874 0.4064)
			(stroke
				(width 0.1524)
				(type default)
			)
			(layer "F.SilkS")
		)
		(fp_line
			(start -0.7874 -0.4064)
			(end 0.7874 -0.4064)
			(stroke
				(width 0.1524)
				(type default)
			)
			(layer "F.SilkS")
		)
		(fp_line
			(start 0.7874 -0.4064)
			(end 0.7874 0.4064)
			(stroke
				(width 0.1524)
				(type default)
			)
			(layer "F.SilkS")
		)
		(fp_line
			(start -0.67945 0.3048)
			(end -0.67945 -0.305054)
			(stroke
				(width 0.1)
				(type default)
			)
			(layer "F.Fab")
		)
		(fp_line
			(start -0.12065 0.3048)
			(end -0.67945 0.3048)
			(stroke
				(width 0.1)
				(type default)
			)
			(layer "F.Fab")
		)
		(fp_line
			(start 0.120396 0.3048)
			(end 0.120396 0.2794)
			(stroke
				(width 0.1)
				(type default)
			)
			(layer "F.Fab")
		)
		(fp_line
			(start 0.67945 0.3048)
			(end 0.120396 0.3048)
			(stroke
				(width 0.1)
				(type default)
			)
			(layer "F.Fab")
		)
		(fp_line
			(start -0.12065 0.2794)
			(end -0.12065 0.3048)
			(stroke
				(width 0.1)
				(type default)
			)
			(layer "F.Fab")
		)
		(fp_line
			(start 0.120396 0.2794)
			(end -0.12065 0.2794)
			(stroke
				(width 0.1)
				(type default)
			)
			(layer "F.Fab")
		)
		(fp_line
			(start -0.12065 -0.2794)
			(end 0.12065 -0.2794)
			(stroke
				(width 0.1)
				(type default)
			)
			(layer "F.Fab")
		)
		(fp_line
			(start 0.12065 -0.2794)
			(end 0.12065 -0.3048)
			(stroke
				(width 0.1)
				(type default)
			)
			(layer "F.Fab")
		)
		(fp_line
			(start 0.12065 -0.3048)
			(end 0.67945 -0.3048)
			(stroke
				(width 0.1)
				(type default)
			)
			(layer "F.Fab")
		)
		(fp_line
			(start 0.67945 -0.3048)
			(end 0.67945 0.3048)
			(stroke
				(width 0.1)
				(type default)
			)
			(layer "F.Fab")
		)
		(fp_line
			(start -0.67945 -0.305054)
			(end -0.12065 -0.305054)
			(stroke
				(width 0.1)
				(type default)
			)
			(layer "F.Fab")
		)
		(fp_line
			(start -0.12065 -0.305054)
			(end -0.12065 -0.2794)
			(stroke
				(width 0.1)
				(type default)
			)
			(layer "F.Fab")
		)
		(pad "1" smd circle
			(at -0.40005 0 270)
			(size 0 0)
			(layers "F.Cu" "F.Mask" "F.Paste")
			(net "OCP_V3_2_P3V3_R3_PWRGD")
		)
		(pad "2" smd circle
			(at 0.40005 0 270)
			(size 0 0)
			(layers "F.Cu" "F.Mask" "F.Paste")
			(net "HP_LVC3_OCP_V3_2_PWRGD")
		)
	)
	(footprint ""
		(layer "F.Cu")
		(at 424.579288 -53.388514 180)
		(property "Reference" "D1"
			(at -1.418844 -2.46126 0)
			(unlocked yes)
			(layer "F.SilkS")
			(effects
				(font
					(size 0.7874 0.5842)
					(thickness 0.1524)
				)
				(justify left)
			)
		)
		(property "Value" ""
			(at 0 0 180)
			(layer "F.Fab")
			(effects
				(font
					(size 1.27 1.27)
				)
			)
		)
		(duplicate_pad_numbers_are_jumpers no)
		(fp_line
			(start 1.584198 1.500124)
			(end 1.584198 -1.500124)
			(stroke
				(width 0.1524)
				(type default)
			)
			(layer "F.SilkS")
		)
		(fp_line
			(start 1.584198 -1.500124)
			(end -1.584198 -1.500124)
			(stroke
				(width 0.1524)
				(type default)
			)
			(layer "F.SilkS")
		)
		(fp_line
			(start -1.584198 1.500124)
			(end 1.584198 1.500124)
			(stroke
				(width 0.1524)
				(type default)
			)
			(layer "F.SilkS")
		)
		(fp_line
			(start -1.584198 -1.500124)
			(end -1.584198 1.500124)
			(stroke
				(width 0.1524)
				(type default)
			)
			(layer "F.SilkS")
		)
		(fp_line
			(start 0.700024 1.500124)
			(end 0.700024 -1.500124)
			(stroke
				(width 0.1)
				(type default)
			)
			(layer "F.Fab")
		)
		(fp_line
			(start 0.700024 -1.500124)
			(end -0.700024 -1.500124)
			(stroke
				(width 0.1)
				(type default)
			)
			(layer "F.Fab")
		)
		(fp_line
			(start -0.700024 1.500124)
			(end 0.700024 1.500124)
			(stroke
				(width 0.1)
				(type default)
			)
			(layer "F.Fab")
		)
		(fp_line
			(start -0.700024 -1.500124)
			(end -0.700024 1.500124)
			(stroke
				(width 0.1)
				(type default)
			)
			(layer "F.Fab")
		)
		(pad "1" smd rect
			(at -0.999998 -0.94996 90)
			(size 0.8128 0.9144)
			(layers "F.Cu" "F.Mask" "F.Paste")
			(net "P3V3")
		)
		(pad "2" smd rect
			(at -0.999998 0.94996 90)
			(size 0.8128 0.9144)
			(layers "F.Cu" "F.Mask" "F.Paste")
			(net "Net_10752")
		)
		(pad "3" smd rect
			(at 0.999998 0 90)
			(size 0.8128 0.9144)
			(layers "F.Cu" "F.Mask" "F.Paste")
			(net "P5V")
		)
	)
)
